(kicad_pcb
	(version 20260206)
	(generator "pcbnew")
	(generator_version "10.0")
	(general
		(thickness 1.6)
		(legacy_teardrops no)
	)
	(paper "A4")
	(title_block
		(title "Bryce Canyon_IOM_IOC_16318-2_OCP.brd")
		(comment 1 "Bryce Canyon / footprints 546-552 of 1605")
	)
	(layers
		(0 "F.Cu" signal "TOP")
		(4 "In1.Cu" signal "L2GND")
		(6 "In2.Cu" signal "L3")
		(8 "In3.Cu" signal "L4VCC")
		(10 "In4.Cu" signal "L5VCC")
		(12 "In5.Cu" signal "L6")
		(14 "In6.Cu" signal "L7GND")
		(2 "B.Cu" signal "BOTTOM")
		(9 "F.Adhes" user "F.Adhesive")
		(11 "B.Adhes" user "B.Adhesive")
		(13 "F.Paste" user "Package Geometry/Pastemask Top")
		(15 "B.Paste" user "Package Geometry/Pastemask Bottom")
		(5 "F.SilkS" user "Ref Des/Silkscreen Top")
		(7 "B.SilkS" user "Ref Des/Silkscreen Bottom")
		(1 "F.Mask" user "Board Geometry/Soldermask Top")
		(3 "B.Mask" user "Board Geometry/Soldermask Bottom")
		(17 "Dwgs.User" user "User.Drawings")
		(19 "Cmts.User" user "User.Comments")
		(21 "Eco1.User" user "User.Eco1")
		(23 "Eco2.User" user "User.Eco2")
		(25 "Edge.Cuts" user "Board Geometry/Outline")
		(27 "Margin" user)
		(31 "F.CrtYd" user "Package Geometry/Place Bound Top")
		(29 "B.CrtYd" user "Package Geometry/Place Bound Bottom")
		(35 "F.Fab" user "Ref Des/Assembly Top")
		(33 "B.Fab" user "Ref Des/Assembly Bottom")
	)
	(footprint ""
		(layer "F.Cu")
		(at 194.880738 -126.905258 180)
		(property "Reference" "C285"
			(at 0 0 180)
			(layer "F.SilkS")
			(hide yes)
			(effects
				(font
					(size 1.27 1.27)
				)
			)
		)
		(property "Value" "SCD1U50V3KX-GP"
			(at 0 -2.8194 180)
			(unlocked yes)
			(layer "F.Fab")
			(hide yes)
			(effects
				(font
					(size 1.016 1.016)
					(thickness 0.1524)
				)
			)
		)
		(property "Device Type" "C603H36"
			(at 0 -4.3434 180)
			(unlocked yes)
			(layer "F.Fab")
			(hide yes)
			(effects
				(font
					(size 1.016 1.016)
					(thickness 0.1524)
				)
			)
		)
		(duplicate_pad_numbers_are_jumpers no)
		(fp_line
			(start 0.508 0)
			(end -0.508 0)
			(stroke
				(width 0.2032)
				(type default)
			)
			(layer "F.SilkS")
		)
		(fp_rect
			(start -0.5842 1.3335)
			(end 0.5842 -1.3335)
			(stroke
				(width 0)
				(type default)
			)
			(fill no)
			(layer "F.CrtYd")
		)
		(fp_rect
			(start -0.5842 1.3335)
			(end 0.5842 -1.3335)
			(stroke
				(width 0)
				(type default)
			)
			(fill no)
			(layer "F.Fab")
		)
		(pad "1" smd custom
			(at 0 -0.762 180)
			(size 0.2159 0.2159)
			(layers "F.Cu" "F.Mask" "F.Paste")
			(net "VT235_VDES_RC")
			(options
				(clearance outline)
				(anchor circle)
			)
			(primitives
				(gr_poly
					(pts
						(arc
							(start -0.3302 -0.4318)
							(mid -0.402042 -0.402042)
							(end -0.4318 -0.3302)
						)
						(arc
							(start -0.4318 0.3302)
							(mid -0.402042 0.402042)
							(end -0.3302 0.4318)
						)
						(arc
							(start 0.3302 0.4318)
							(mid 0.402042 0.402042)
							(end 0.4318 0.3302)
						)
						(arc
							(start 0.4318 -0.3302)
							(mid 0.402042 -0.402042)
							(end 0.3302 -0.4318)
						)
					)
					(width 0)
					(fill yes)
				)
			)
		)
		(pad "2" smd custom
			(at 0 0.762 180)
			(size 0.2159 0.2159)
			(layers "F.Cu" "F.Mask" "F.Paste")
			(net "VT235_VDES_RCC")
			(options
				(clearance outline)
				(anchor circle)
			)
			(primitives
				(gr_poly
					(pts
						(arc
							(start -0.3302 -0.4318)
							(mid -0.402042 -0.402042)
							(end -0.4318 -0.3302)
						)
						(arc
							(start -0.4318 0.3302)
							(mid -0.402042 0.402042)
							(end -0.3302 0.4318)
						)
						(arc
							(start 0.3302 0.4318)
							(mid 0.402042 0.402042)
							(end 0.4318 0.3302)
						)
						(arc
							(start 0.4318 -0.3302)
							(mid 0.402042 -0.402042)
							(end 0.3302 -0.4318)
						)
					)
					(width 0)
					(fill yes)
				)
			)
		)
	)
	(footprint ""
		(layer "F.Cu")
		(at 39.0398 -158.623 180)
		(property "Reference" "R328"
			(at 0 0 180)
			(layer "F.SilkS")
			(hide yes)
			(effects
				(font
					(size 1.27 1.27)
				)
			)
		)
		(property "Value" "0R2J-2-GP"
			(at 0.064008 -3.993896 180)
			(unlocked yes)
			(layer "F.Fab")
			(hide yes)
			(effects
				(font
					(size 1.016 1.016)
					(thickness 0.1524)
				)
			)
		)
		(property "Device Type" "R402H16"
			(at 0.064008 -5.517896 180)
			(unlocked yes)
			(layer "F.Fab")
			(hide yes)
			(effects
				(font
					(size 1.016 1.016)
					(thickness 0.1524)
				)
			)
		)
		(duplicate_pad_numbers_are_jumpers no)
		(fp_line
			(start 0.508 -0.9398)
			(end -0.508 -0.9398)
			(stroke
				(width 0.1524)
				(type default)
			)
			(layer "F.SilkS")
		)
		(fp_line
			(start -0.508 -0.9398)
			(end -0.508 0.9398)
			(stroke
				(width 0.1524)
				(type default)
			)
			(layer "F.SilkS")
		)
		(fp_rect
			(start -0.508 0.9398)
			(end 0.508 -0.9398)
			(stroke
				(width 0)
				(type default)
			)
			(fill no)
			(layer "F.CrtYd")
		)
		(fp_rect
			(start -0.508 0.9398)
			(end 0.508 -0.9398)
			(stroke
				(width 0)
				(type default)
			)
			(fill no)
			(layer "F.Fab")
		)
		(pad "1" smd custom
			(at 0 -0.4445 180)
			(size 0.1397 0.1397)
			(layers "F.Cu" "F.Mask" "F.Paste")
			(net "UART_COMP_OUT_TX_R")
			(options
				(clearance outline)
				(anchor circle)
			)
			(primitives
				(gr_poly
					(pts
						(arc
							(start -0.1778 -0.2794)
							(mid -0.249642 -0.249642)
							(end -0.2794 -0.1778)
						)
						(arc
							(start -0.2794 0.1778)
							(mid -0.249642 0.249642)
							(end -0.1778 0.2794)
						)
						(arc
							(start 0.1778 0.2794)
							(mid 0.249642 0.249642)
							(end 0.2794 0.1778)
						)
						(arc
							(start 0.2794 -0.1778)
							(mid 0.249642 -0.249642)
							(end 0.1778 -0.2794)
						)
					)
					(width 0)
					(fill yes)
				)
			)
		)
		(pad "2" smd custom
			(at 0 0.4445 180)
			(size 0.1397 0.1397)
			(layers "F.Cu" "F.Mask" "F.Paste")
			(net "UART_COMP_OUT_TX")
			(options
				(clearance outline)
				(anchor circle)
			)
			(primitives
				(gr_poly
					(pts
						(arc
							(start -0.1778 -0.2794)
							(mid -0.249642 -0.249642)
							(end -0.2794 -0.1778)
						)
						(arc
							(start -0.2794 0.1778)
							(mid -0.249642 0.249642)
							(end -0.1778 0.2794)
						)
						(arc
							(start 0.1778 0.2794)
							(mid 0.249642 0.249642)
							(end 0.2794 0.1778)
						)
						(arc
							(start 0.2794 -0.1778)
							(mid 0.249642 -0.249642)
							(end 0.1778 -0.2794)
						)
					)
					(width 0)
					(fill yes)
				)
			)
		)
	)
	(footprint ""
		(layer "F.Cu")
		(at 213.2076 -120.777 90)
		(property "Reference" "C251"
			(at 0 0 90)
			(layer "F.SilkS")
			(hide yes)
			(effects
				(font
					(size 1.27 1.27)
				)
			)
		)
		(property "Value" "SCD1U16V2KX-3GP"
			(at 1.1811 -2.7051 90)
			(unlocked yes)
			(layer "F.Fab")
			(hide yes)
			(effects
				(font
					(size 1.016 1.016)
					(thickness 0.1524)
				)
			)
		)
		(property "Device Type" "C402H22"
			(at 1.1811 -4.2291 90)
			(unlocked yes)
			(layer "F.Fab")
			(hide yes)
			(effects
				(font
					(size 1.016 1.016)
					(thickness 0.1524)
				)
			)
		)
		(duplicate_pad_numbers_are_jumpers no)
		(fp_rect
			(start -0.4318 0.9525)
			(end 0.4318 -0.9525)
			(stroke
				(width 0)
				(type default)
			)
			(fill no)
			(layer "F.CrtYd")
		)
		(fp_rect
			(start -0.4318 0.9525)
			(end 0.4318 -0.9525)
			(stroke
				(width 0)
				(type default)
			)
			(fill no)
			(layer "F.Fab")
		)
		(pad "1" smd custom
			(at 0 -0.4445 90)
			(size 0.1524 0.1524)
			(layers "F.Cu" "F.Mask" "F.Paste")
			(net "P1V5_OUT")
			(options
				(clearance outline)
				(anchor circle)
			)
			(primitives
				(gr_poly
					(pts
						(arc
							(start 0.3048 -0.2032)
							(mid 0.275042 -0.275042)
							(end 0.2032 -0.3048)
						)
						(arc
							(start -0.2032 -0.3048)
							(mid -0.275042 -0.275042)
							(end -0.3048 -0.2032)
						)
						(arc
							(start -0.3048 0.2032)
							(mid -0.275042 0.275042)
							(end -0.2032 0.3048)
						)
						(arc
							(start 0.2032 0.3048)
							(mid 0.275042 0.275042)
							(end 0.3048 0.2032)
						)
					)
					(width 0)
					(fill yes)
				)
			)
		)
		(pad "2" smd custom
			(at 0 0.4445 90)
			(size 0.1524 0.1524)
			(layers "F.Cu" "F.Mask" "F.Paste")
			(net "GND")
			(options
				(clearance outline)
				(anchor circle)
			)
			(primitives
				(gr_poly
					(pts
						(arc
							(start 0.3048 -0.2032)
							(mid 0.275042 -0.275042)
							(end 0.2032 -0.3048)
						)
						(arc
							(start -0.2032 -0.3048)
							(mid -0.275042 -0.275042)
							(end -0.3048 -0.2032)
						)
						(arc
							(start -0.3048 0.2032)
							(mid -0.275042 0.275042)
							(end -0.2032 0.3048)
						)
						(arc
							(start 0.2032 0.3048)
							(mid 0.275042 0.275042)
							(end 0.3048 0.2032)
						)
					)
					(width 0)
					(fill yes)
				)
			)
		)
	)
	(footprint ""
		(layer "F.Cu")
		(at 43.3578 -131.7498 180)
		(property "Reference" "R262"
			(at 0 0 180)
			(layer "F.SilkS")
			(hide yes)
			(effects
				(font
					(size 1.27 1.27)
				)
			)
		)
		(property "Value" "4K7R2F-GP"
			(at 0.064008 -3.993896 180)
			(unlocked yes)
			(layer "F.Fab")
			(hide yes)
			(effects
				(font
					(size 1.016 1.016)
					(thickness 0.1524)
				)
			)
		)
		(property "Device Type" "R402H16"
			(at 0.064008 -5.517896 180)
			(unlocked yes)
			(layer "F.Fab")
			(hide yes)
			(effects
				(font
					(size 1.016 1.016)
					(thickness 0.1524)
				)
			)
		)
		(duplicate_pad_numbers_are_jumpers no)
		(fp_line
			(start 0.508 -0.9398)
			(end -0.508 -0.9398)
			(stroke
				(width 0.1524)
				(type default)
			)
			(layer "F.SilkS")
		)
		(fp_line
			(start -0.508 -0.9398)
			(end -0.508 0.9398)
			(stroke
				(width 0.1524)
				(type default)
			)
			(layer "F.SilkS")
		)
		(fp_rect
			(start -0.508 0.9398)
			(end 0.508 -0.9398)
			(stroke
				(width 0)
				(type default)
			)
			(fill no)
			(layer "F.CrtYd")
		)
		(fp_rect
			(start -0.508 0.9398)
			(end 0.508 -0.9398)
			(stroke
				(width 0)
				(type default)
			)
			(fill no)
			(layer "F.Fab")
		)
		(pad "1" smd custom
			(at 0 -0.4445 180)
			(size 0.1397 0.1397)
			(layers "F.Cu" "F.Mask" "F.Paste")
			(net "P3V3_STBY")
			(options
				(clearance outline)
				(anchor circle)
			)
			(primitives
				(gr_poly
					(pts
						(arc
							(start -0.1778 -0.2794)
							(mid -0.249642 -0.249642)
							(end -0.2794 -0.1778)
						)
						(arc
							(start -0.2794 0.1778)
							(mid -0.249642 0.249642)
							(end -0.1778 0.2794)
						)
						(arc
							(start 0.1778 0.2794)
							(mid 0.249642 0.249642)
							(end 0.2794 0.1778)
						)
						(arc
							(start 0.2794 -0.1778)
							(mid 0.249642 -0.249642)
							(end 0.1778 -0.2794)
						)
					)
					(width 0)
					(fill yes)
				)
			)
		)
		(pad "2" smd custom
			(at 0 0.4445 180)
			(size 0.1397 0.1397)
			(layers "F.Cu" "F.Mask" "F.Paste")
			(net "BMC_GPIOY0")
			(options
				(clearance outline)
				(anchor circle)
			)
			(primitives
				(gr_poly
					(pts
						(arc
							(start -0.1778 -0.2794)
							(mid -0.249642 -0.249642)
							(end -0.2794 -0.1778)
						)
						(arc
							(start -0.2794 0.1778)
							(mid -0.249642 0.249642)
							(end -0.1778 0.2794)
						)
						(arc
							(start 0.1778 0.2794)
							(mid 0.249642 0.249642)
							(end 0.2794 0.1778)
						)
						(arc
							(start 0.2794 -0.1778)
							(mid 0.249642 -0.249642)
							(end 0.1778 -0.2794)
						)
					)
					(width 0)
					(fill yes)
				)
			)
		)
	)
	(footprint ""
		(layer "F.Cu")
		(at 36.0934 -132.4864)
		(property "Reference" "R312"
			(at 0 0 0)
			(layer "F.SilkS")
			(hide yes)
			(effects
				(font
					(size 1.27 1.27)
				)
			)
		)
		(property "Value" "0R2J-2-GP"
			(at 0.064008 -3.993896 0)
			(unlocked yes)
			(layer "F.Fab")
			(hide yes)
			(effects
				(font
					(size 1.016 1.016)
					(thickness 0.1524)
				)
			)
		)
		(property "Device Type" "R402H16"
			(at 0.064008 -5.517896 0)
			(unlocked yes)
			(layer "F.Fab")
			(hide yes)
			(effects
				(font
					(size 1.016 1.016)
					(thickness 0.1524)
				)
			)
		)
		(duplicate_pad_numbers_are_jumpers no)
		(fp_line
			(start -0.508 -0.9398)
			(end -0.508 0.9398)
			(stroke
				(width 0.1524)
				(type default)
			)
			(layer "F.SilkS")
		)
		(fp_line
			(start 0.508 -0.9398)
			(end -0.508 -0.9398)
			(stroke
				(width 0.1524)
				(type default)
			)
			(layer "F.SilkS")
		)
		(fp_rect
			(start -0.508 0.9398)
			(end 0.508 -0.9398)
			(stroke
				(width 0)
				(type default)
			)
			(fill no)
			(layer "F.CrtYd")
		)
		(fp_rect
			(start -0.508 0.9398)
			(end 0.508 -0.9398)
			(stroke
				(width 0)
				(type default)
			)
			(fill no)
			(layer "F.Fab")
		)
		(pad "1" smd custom
			(at 0 -0.4445)
			(size 0.1397 0.1397)
			(layers "F.Cu" "F.Mask" "F.Paste")
			(net "CLKIN_24M_BMC")
			(options
				(clearance outline)
				(anchor circle)
			)
			(primitives
				(gr_poly
					(pts
						(arc
							(start -0.1778 -0.2794)
							(mid -0.249642 -0.249642)
							(end -0.2794 -0.1778)
						)
						(arc
							(start -0.2794 0.1778)
							(mid -0.249642 0.249642)
							(end -0.1778 0.2794)
						)
						(arc
							(start 0.1778 0.2794)
							(mid 0.249642 0.249642)
							(end 0.2794 0.1778)
						)
						(arc
							(start 0.2794 -0.1778)
							(mid 0.249642 -0.249642)
							(end 0.1778 -0.2794)
						)
					)
					(width 0)
					(fill yes)
				)
			)
		)
		(pad "2" smd custom
			(at 0 0.4445)
			(size 0.1397 0.1397)
			(layers "F.Cu" "F.Mask" "F.Paste")
			(net "OSC_OUT")
			(options
				(clearance outline)
				(anchor circle)
			)
			(primitives
				(gr_poly
					(pts
						(arc
							(start -0.1778 -0.2794)
							(mid -0.249642 -0.249642)
							(end -0.2794 -0.1778)
						)
						(arc
							(start -0.2794 0.1778)
							(mid -0.249642 0.249642)
							(end -0.1778 0.2794)
						)
						(arc
							(start 0.1778 0.2794)
							(mid 0.249642 0.249642)
							(end 0.2794 0.1778)
						)
						(arc
							(start 0.2794 -0.1778)
							(mid 0.249642 -0.249642)
							(end 0.1778 -0.2794)
						)
					)
					(width 0)
					(fill yes)
				)
			)
		)
	)
	(footprint ""
		(layer "F.Cu")
		(at 77.2922 -150.3426 180)
		(property "Reference" "R717"
			(at 0 0 180)
			(layer "F.SilkS")
			(hide yes)
			(effects
				(font
					(size 1.27 1.27)
				)
			)
		)
		(property "Value" "0R2J-2-GP"
			(at 0.064008 -3.993896 180)
			(unlocked yes)
			(layer "F.Fab")
			(hide yes)
			(effects
				(font
					(size 1.016 1.016)
					(thickness 0.1524)
				)
			)
		)
		(property "Device Type" "R402H16"
			(at 0.064008 -5.517896 180)
			(unlocked yes)
			(layer "F.Fab")
			(hide yes)
			(effects
				(font
					(size 1.016 1.016)
					(thickness 0.1524)
				)
			)
		)
		(duplicate_pad_numbers_are_jumpers no)
		(fp_line
			(start 0.508 -0.9398)
			(end -0.508 -0.9398)
			(stroke
				(width 0.1524)
				(type default)
			)
			(layer "F.SilkS")
		)
		(fp_line
			(start -0.508 -0.9398)
			(end -0.508 0.9398)
			(stroke
				(width 0.1524)
				(type default)
			)
			(layer "F.SilkS")
		)
		(fp_rect
			(start -0.508 0.9398)
			(end 0.508 -0.9398)
			(stroke
				(width 0)
				(type default)
			)
			(fill no)
			(layer "F.CrtYd")
		)
		(fp_rect
			(start -0.508 0.9398)
			(end 0.508 -0.9398)
			(stroke
				(width 0)
				(type default)
			)
			(fill no)
			(layer "F.Fab")
		)
		(pad "1" smd custom
			(at 0 -0.4445 180)
			(size 0.1397 0.1397)
			(layers "F.Cu" "F.Mask" "F.Paste")
			(net "COMP_TO_BMC_RESET_R")
			(options
				(clearance outline)
				(anchor circle)
			)
			(primitives
				(gr_poly
					(pts
						(arc
							(start -0.1778 -0.2794)
							(mid -0.249642 -0.249642)
							(end -0.2794 -0.1778)
						)
						(arc
							(start -0.2794 0.1778)
							(mid -0.249642 0.249642)
							(end -0.1778 0.2794)
						)
						(arc
							(start 0.1778 0.2794)
							(mid 0.249642 0.249642)
							(end 0.2794 0.1778)
						)
						(arc
							(start 0.2794 -0.1778)
							(mid 0.249642 -0.249642)
							(end 0.1778 -0.2794)
						)
					)
					(width 0)
					(fill yes)
				)
			)
		)
		(pad "2" smd custom
			(at 0 0.4445 180)
			(size 0.1397 0.1397)
			(layers "F.Cu" "F.Mask" "F.Paste")
			(net "COMP_TO_BMC_RESET")
			(options
				(clearance outline)
				(anchor circle)
			)
			(primitives
				(gr_poly
					(pts
						(arc
							(start -0.1778 -0.2794)
							(mid -0.249642 -0.249642)
							(end -0.2794 -0.1778)
						)
						(arc
							(start -0.2794 0.1778)
							(mid -0.249642 0.249642)
							(end -0.1778 0.2794)
						)
						(arc
							(start 0.1778 0.2794)
							(mid 0.249642 0.249642)
							(end 0.2794 0.1778)
						)
						(arc
							(start 0.2794 -0.1778)
							(mid 0.249642 -0.249642)
							(end 0.1778 -0.2794)
						)
					)
					(width 0)
					(fill yes)
				)
			)
		)
	)
	(footprint ""
		(layer "F.Cu")
		(at 180.6321 -48.1457)
		(property "Reference" "R672"
			(at 0 0 0)
			(layer "F.SilkS")
			(hide yes)
			(effects
				(font
					(size 1.27 1.27)
				)
			)
		)
		(property "Value" "10KR2F-2-GP"
			(at 0.064008 -3.993896 0)
			(unlocked yes)
			(layer "F.Fab")
			(hide yes)
			(effects
				(font
					(size 1.016 1.016)
					(thickness 0.1524)
				)
			)
		)
		(property "Device Type" "R402H16"
			(at 0.064008 -5.517896 0)
			(unlocked yes)
			(layer "F.Fab")
			(hide yes)
			(effects
				(font
					(size 1.016 1.016)
					(thickness 0.1524)
				)
			)
		)
		(duplicate_pad_numbers_are_jumpers no)
		(fp_line
			(start -0.508 -0.9398)
			(end -0.508 0.9398)
			(stroke
				(width 0.1524)
				(type default)
			)
			(layer "F.SilkS")
		)
		(fp_line
			(start 0.508 -0.9398)
			(end -0.508 -0.9398)
			(stroke
				(width 0.1524)
				(type default)
			)
			(layer "F.SilkS")
		)
		(fp_rect
			(start -0.508 0.9398)
			(end 0.508 -0.9398)
			(stroke
				(width 0)
				(type default)
			)
			(fill no)
			(layer "F.CrtYd")
		)
		(fp_rect
			(start -0.508 0.9398)
			(end 0.508 -0.9398)
			(stroke
				(width 0)
				(type default)
			)
			(fill no)
			(layer "F.Fab")
		)
		(pad "1" smd custom
			(at 0 -0.4445)
			(size 0.1397 0.1397)
			(layers "F.Cu" "F.Mask" "F.Paste")
			(net "XM_ADDR_6")
			(options
				(clearance outline)
				(anchor circle)
			)
			(primitives
				(gr_poly
					(pts
						(arc
							(start -0.1778 -0.2794)
							(mid -0.249642 -0.249642)
							(end -0.2794 -0.1778)
						)
						(arc
							(start -0.2794 0.1778)
							(mid -0.249642 0.249642)
							(end -0.1778 0.2794)
						)
						(arc
							(start 0.1778 0.2794)
							(mid 0.249642 0.249642)
							(end 0.2794 0.1778)
						)
						(arc
							(start 0.2794 -0.1778)
							(mid 0.249642 -0.249642)
							(end 0.1778 -0.2794)
						)
					)
					(width 0)
					(fill yes)
				)
			)
		)
		(pad "2" smd custom
			(at 0 0.4445)
			(size 0.1397 0.1397)
			(layers "F.Cu" "F.Mask" "F.Paste")
			(net "GND")
			(options
				(clearance outline)
				(anchor circle)
			)
			(primitives
				(gr_poly
					(pts
						(arc
							(start -0.1778 -0.2794)
							(mid -0.249642 -0.249642)
							(end -0.2794 -0.1778)
						)
						(arc
							(start -0.2794 0.1778)
							(mid -0.249642 0.249642)
							(end -0.1778 0.2794)
						)
						(arc
							(start 0.1778 0.2794)
							(mid 0.249642 0.249642)
							(end 0.2794 0.1778)
						)
						(arc
							(start 0.2794 -0.1778)
							(mid 0.249642 -0.249642)
							(end 0.1778 -0.2794)
						)
					)
					(width 0)
					(fill yes)
				)
			)
		)
	)
)
